# T6G (Grand Teton) — schematic netlist excerpt (pin names and nets, part order shuffled) for the footprints in the layout excerpt that follows; sources: Cadence DE-HDL packaged netlist, KiCad conversion of 04192023_DAF0TMB3IC0_F0TG_MB_C_brd_V02_OCP.brd

H12  HOLE  EMPTY  pkg TH  page 230 : \1\ = GND
PC137  Q_CAP  0.22UF 16V 10% X7R  pkg 0402  page 203 : A = SW_PVDDCR_CPU1_P0_BOOT5_R ; B = SW_PVDDCR_CPU1_P0_BOOTR5
PC2205  Q_CAP  2.2UF 16V 20% X7R  pkg C0603  page 147 : A = P12V_E1S_AVIN_PD_0 ; B = GND

(kicad_pcb
	(version 20260206)
	(generator "pcbnew")
	(generator_version "10.0")
	(general
		(thickness 1.6)
		(legacy_teardrops no)
	)
	(paper "A4")
	(title_block
		(title "04192023_DAF0TMB3IC0_F0TG_MB_C_brd_V02_OCP.brd")
		(comment 1 "Grand Teton / footprints 3287-3289 of 8354")
	)
	(layers
		(0 "F.Cu" signal "TOP")
		(4 "In1.Cu" signal "GND")
		(6 "In2.Cu" signal "IN1")
		(8 "In3.Cu" signal "GND1")
		(10 "In4.Cu" signal "IN2")
		(12 "In5.Cu" signal "GND2")
		(14 "In6.Cu" signal "IN3")
		(16 "In7.Cu" signal "GND3")
		(18 "In8.Cu" signal "VCC")
		(20 "In9.Cu" signal "VCC1")
		(22 "In10.Cu" signal "GND4")
		(24 "In11.Cu" signal "IN4")
		(26 "In12.Cu" signal "GND5")
		(28 "In13.Cu" signal "IN5")
		(30 "In14.Cu" signal "GND6")
		(32 "In15.Cu" signal "IN6")
		(34 "In16.Cu" signal "GND7")
		(2 "B.Cu" signal "BOTTOM")
		(9 "F.Adhes" user "F.Adhesive")
		(11 "B.Adhes" user "B.Adhesive")
		(13 "F.Paste" user "Package Geometry/Pastemask Top")
		(15 "B.Paste" user "Package Geometry/Pastemask Bottom")
		(5 "F.SilkS" user "Ref Des/Silkscreen Top")
		(7 "B.SilkS" user "Ref Des/Silkscreen Bottom")
		(1 "F.Mask" user "Board Geometry/Soldermask Top")
		(3 "B.Mask" user "Board Geometry/Soldermask Bottom")
		(17 "Dwgs.User" user "User.Drawings")
		(19 "Cmts.User" user "User.Comments")
		(21 "Eco1.User" user "User.Eco1")
		(23 "Eco2.User" user "User.Eco2")
		(25 "Edge.Cuts" user "Board Geometry/Outline")
		(27 "Margin" user)
		(31 "F.CrtYd" user "Package Geometry/Place Bound Top")
		(29 "B.CrtYd" user "Package Geometry/Place Bound Bottom")
		(35 "F.Fab" user "Ref Des/Assembly Top")
		(33 "B.Fab" user "Ref Des/Assembly Bottom")
	)
	(footprint ""
		(layer "F.Cu")
		(at 345.176094 -339.676232 -90)
		(property "Reference" "PC137"
			(at 0 0 270)
			(layer "F.SilkS")
			(hide yes)
			(effects
				(font
					(size 1.27 1.27)
				)
			)
		)
		(property "Value" ""
			(at 0 0 270)
			(layer "F.Fab")
			(effects
				(font
					(size 1.27 1.27)
				)
			)
		)
		(duplicate_pad_numbers_are_jumpers no)
		(fp_line
			(start -0.7874 0.4064)
			(end -0.7874 -0.4064)
			(stroke
				(width 0.1524)
				(type default)
			)
			(layer "F.SilkS")
		)
		(fp_line
			(start 0.7874 0.4064)
			(end -0.7874 0.4064)
			(stroke
				(width 0.1524)
				(type default)
			)
			(layer "F.SilkS")
		)
		(fp_line
			(start -0.7874 -0.4064)
			(end 0.7874 -0.4064)
			(stroke
				(width 0.1524)
				(type default)
			)
			(layer "F.SilkS")
		)
		(fp_line
			(start 0.7874 -0.4064)
			(end 0.7874 0.4064)
			(stroke
				(width 0.1524)
				(type default)
			)
			(layer "F.SilkS")
		)
		(fp_line
			(start -0.67945 0.3048)
			(end -0.67945 -0.305054)
			(stroke
				(width 0.1)
				(type default)
			)
			(layer "F.Fab")
		)
		(fp_line
			(start -0.12065 0.3048)
			(end -0.67945 0.3048)
			(stroke
				(width 0.1)
				(type default)
			)
			(layer "F.Fab")
		)
		(fp_line
			(start 0.120396 0.3048)
			(end 0.120396 0.2794)
			(stroke
				(width 0.1)
				(type default)
			)
			(layer "F.Fab")
		)
		(fp_line
			(start 0.67945 0.3048)
			(end 0.120396 0.3048)
			(stroke
				(width 0.1)
				(type default)
			)
			(layer "F.Fab")
		)
		(fp_line
			(start -0.12065 0.2794)
			(end -0.12065 0.3048)
			(stroke
				(width 0.1)
				(type default)
			)
			(layer "F.Fab")
		)
		(fp_line
			(start 0.120396 0.2794)
			(end -0.12065 0.2794)
			(stroke
				(width 0.1)
				(type default)
			)
			(layer "F.Fab")
		)
		(fp_line
			(start -0.12065 -0.2794)
			(end 0.12065 -0.2794)
			(stroke
				(width 0.1)
				(type default)
			)
			(layer "F.Fab")
		)
		(fp_line
			(start 0.12065 -0.2794)
			(end 0.12065 -0.3048)
			(stroke
				(width 0.1)
				(type default)
			)
			(layer "F.Fab")
		)
		(fp_line
			(start 0.12065 -0.3048)
			(end 0.67945 -0.3048)
			(stroke
				(width 0.1)
				(type default)
			)
			(layer "F.Fab")
		)
		(fp_line
			(start 0.67945 -0.3048)
			(end 0.67945 0.3048)
			(stroke
				(width 0.1)
				(type default)
			)
			(layer "F.Fab")
		)
		(fp_line
			(start -0.67945 -0.305054)
			(end -0.12065 -0.305054)
			(stroke
				(width 0.1)
				(type default)
			)
			(layer "F.Fab")
		)
		(fp_line
			(start -0.12065 -0.305054)
			(end -0.12065 -0.2794)
			(stroke
				(width 0.1)
				(type default)
			)
			(layer "F.Fab")
		)
		(pad "1" smd circle
			(at -0.40005 0 270)
			(size 0 0)
			(layers "F.Cu" "F.Mask" "F.Paste")
			(net "SW_PVDDCR_CPU1_P0_BOOT5_R")
		)
		(pad "2" smd circle
			(at 0.40005 0 270)
			(size 0 0)
			(layers "F.Cu" "F.Mask" "F.Paste")
			(net "SW_PVDDCR_CPU1_P0_BOOTR5")
		)
	)
	(footprint ""
		(layer "F.Cu")
		(at 251.009912 -54.440582 90)
		(property "Reference" "PC2205"
			(at 0 0 90)
			(layer "F.SilkS")
			(hide yes)
			(effects
				(font
					(size 1.27 1.27)
				)
			)
		)
		(property "Value" ""
			(at 0 0 90)
			(layer "F.Fab")
			(effects
				(font
					(size 1.27 1.27)
				)
			)
		)
		(duplicate_pad_numbers_are_jumpers no)
		(fp_line
			(start 1.2954 -0.5842)
			(end 1.2954 0.5842)
			(stroke
				(width 0.1524)
				(type default)
			)
			(layer "F.SilkS")
		)
		(fp_line
			(start -1.2954 -0.5842)
			(end 1.2954 -0.5842)
			(stroke
				(width 0.1524)
				(type default)
			)
			(layer "F.SilkS")
		)
		(fp_line
			(start 1.2954 0.5842)
			(end -1.2954 0.5842)
			(stroke
				(width 0.1524)
				(type default)
			)
			(layer "F.SilkS")
		)
		(fp_line
			(start -1.2954 0.5842)
			(end -1.2954 -0.5842)
			(stroke
				(width 0.1524)
				(type default)
			)
			(layer "F.SilkS")
		)
		(fp_line
			(start 0.8636 -0.4572)
			(end 0.8636 -0.4064)
			(stroke
				(width 0.1)
				(type default)
			)
			(layer "F.Fab")
		)
		(fp_line
			(start -0.8636 -0.4572)
			(end 0.8636 -0.4572)
			(stroke
				(width 0.1)
				(type default)
			)
			(layer "F.Fab")
		)
		(fp_line
			(start 1.1938 -0.4064)
			(end 1.1938 0.4064)
			(stroke
				(width 0.1)
				(type default)
			)
			(layer "F.Fab")
		)
		(fp_line
			(start 0.8636 -0.4064)
			(end 1.1938 -0.4064)
			(stroke
				(width 0.1)
				(type default)
			)
			(layer "F.Fab")
		)
		(fp_line
			(start -0.8636 -0.4064)
			(end -0.8636 -0.4572)
			(stroke
				(width 0.1)
				(type default)
			)
			(layer "F.Fab")
		)
		(fp_line
			(start -1.1938 -0.4064)
			(end -0.8636 -0.4064)
			(stroke
				(width 0.1)
				(type default)
			)
			(layer "F.Fab")
		)
		(fp_line
			(start 1.1938 0.4064)
			(end 0.8636 0.4064)
			(stroke
				(width 0.1)
				(type default)
			)
			(layer "F.Fab")
		)
		(fp_line
			(start 0.8636 0.4064)
			(end 0.8636 0.4572)
			(stroke
				(width 0.1)
				(type default)
			)
			(layer "F.Fab")
		)
		(fp_line
			(start -0.8636 0.4064)
			(end -1.1938 0.4064)
			(stroke
				(width 0.1)
				(type default)
			)
			(layer "F.Fab")
		)
		(fp_line
			(start -1.1938 0.4064)
			(end -1.1938 -0.4064)
			(stroke
				(width 0.1)
				(type default)
			)
			(layer "F.Fab")
		)
		(fp_line
			(start 0.8636 0.4572)
			(end -0.8636 0.4572)
			(stroke
				(width 0.1)
				(type default)
			)
			(layer "F.Fab")
		)
		(fp_line
			(start -0.8636 0.4572)
			(end -0.8636 0.4064)
			(stroke
				(width 0.1)
				(type default)
			)
			(layer "F.Fab")
		)
		(pad "1" smd rect
			(at -0.7366 0)
			(size 0.7112 0.8128)
			(layers "F.Cu" "F.Mask" "F.Paste")
			(net "P12V_E1S_AVIN_PD_0")
		)
		(pad "2" smd rect
			(at 0.7366 0)
			(size 0.7112 0.8128)
			(layers "F.Cu" "F.Mask" "F.Paste")
			(net "GND")
		)
	)
	(footprint ""
		(layer "F.Cu")
		(at 249.899932 -290.89985)
		(property "Reference" "H12"
			(at 3.83413 0.127254 0)
			(unlocked yes)
			(layer "F.SilkS")
			(effects
				(font
					(size 0.7874 0.5842)
					(thickness 0.1524)
				)
				(justify left)
			)
		)
		(property "Value" ""
			(at 0 0 0)
			(layer "F.Fab")
			(effects
				(font
					(size 1.27 1.27)
				)
			)
		)
		(duplicate_pad_numbers_are_jumpers no)
		(pad "1" thru_hole circle
			(at 0 0)
			(size 6.1976 6.1976)
			(drill 3.7338)
			(layers "*.Cu" "*.Mask")
			(remove_unused_layers no)
			(net "GND")
			(clearance -0.9779)
			(padstack
				(mode front_inner_back)
				(layer "Inner"
					(shape circle)
					(size 5.5372 5.5372)
					(clearance -0.6477)
				)
				(layer "B.Cu"
					(shape circle)
					(size 6.1976 6.1976)
					(clearance -0.9779)
				)
			)
		)
	)
)
